(kicad_pcb
	(version 20241229)
	(generator "pcbnew")
	(generator_version "9.0")
	(general
		(thickness 1.6296)
		(legacy_teardrops no)
	)
	(paper "A3")
	(title_block
		(title "Thunderbolt to 10GbE adapter")
		(date "2026-04-21")
		(rev "1.1.0")
		(company "Antmicro Ltd")
		(comment 1 "www.antmicro.com")
		(comment 9 "footprints 243-247 of 703")
	)
	(layers
		(0 "F.Cu" signal)
		(4 "In1.Cu" signal)
		(6 "In2.Cu" signal)
		(8 "In3.Cu" signal)
		(10 "In4.Cu" signal)
		(12 "In5.Cu" signal)
		(14 "In6.Cu" signal)
		(2 "B.Cu" signal)
		(9 "F.Adhes" user "F.Adhesive")
		(11 "B.Adhes" user "B.Adhesive")
		(13 "F.Paste" user)
		(15 "B.Paste" user)
		(5 "F.SilkS" user "F.Silkscreen")
		(7 "B.SilkS" user "B.Silkscreen")
		(1 "F.Mask" user)
		(3 "B.Mask" user)
		(17 "Dwgs.User" user "User.Drawings")
		(19 "Cmts.User" user "User.Comments")
		(21 "Eco1.User" user "User.Eco1")
		(23 "Eco2.User" user "User.Eco2")
		(25 "Edge.Cuts" user)
		(27 "Margin" user)
		(31 "F.CrtYd" user "F.Courtyard")
		(29 "B.CrtYd" user "B.Courtyard")
		(35 "F.Fab" user)
		(33 "B.Fab" user)
	)
	(footprint "antmicro-footprints:R_0402_1005Metric"
		(layer "F.Cu")
		(at 116.4 105.1 180)
		(descr "Resistor SMD 0402")
		(tags "resistor SMD 0402")
		(property "Reference" "R21"
			(at 0 8.1 180)
			(layer "F.SilkS")
			(effects
				(font
					(size 0.7 0.7)
					(thickness 0.15)
				)
			)
		)
		(property "Value" "R_40k2_0402"
			(at -1.011843 1.772047 180)
			(layer "F.Fab")
			(effects
				(font
					(size 0.7 0.7)
					(thickness 0.15)
				)
				(justify left bottom)
			)
		)
		(property "Datasheet" "https://www.bourns.com/docs/product-datasheets/cr.pdf"
			(at 0 0 180)
			(layer "F.Fab")
			(hide yes)
			(effects
				(font
					(size 1.27 1.27)
					(thickness 0.15)
				)
			)
		)
		(property "Description" "SMD Chip Resistor, 40.2 kohm, ± 1%, 63 mW, 0402 [1005 Metric], Thick Film, General Purpose"
			(at 0 0 180)
			(layer "F.Fab")
			(hide yes)
			(effects
				(font
					(size 1.27 1.27)
					(thickness 0.15)
				)
			)
		)
		(property "MPN" "CR0402-FX-4022GLF"
			(at 0 0 180)
			(unlocked yes)
			(layer "F.Fab")
			(hide yes)
			(effects
				(font
					(size 1 1)
					(thickness 0.15)
				)
			)
		)
		(property "Manufacturer" "Bourns"
			(at 0 0 180)
			(unlocked yes)
			(layer "F.Fab")
			(hide yes)
			(effects
				(font
					(size 1 1)
					(thickness 0.15)
				)
			)
		)
		(property "License" "Apache-2.0"
			(at 0 0 180)
			(unlocked yes)
			(layer "F.Fab")
			(hide yes)
			(effects
				(font
					(size 1 1)
					(thickness 0.15)
				)
			)
		)
		(property "Val" "40k2"
			(at 0 0 180)
			(unlocked yes)
			(layer "F.Fab")
			(hide yes)
			(effects
				(font
					(size 1 1)
					(thickness 0.15)
				)
			)
		)
		(property "Tolerance" "1%"
			(at 0 0 180)
			(unlocked yes)
			(layer "F.Fab")
			(hide yes)
			(effects
				(font
					(size 1 1)
					(thickness 0.15)
				)
			)
		)
		(property "Author" "Antmicro"
			(at 0 0 180)
			(unlocked yes)
			(layer "F.Fab")
			(hide yes)
			(effects
				(font
					(size 1 1)
					(thickness 0.15)
				)
			)
		)
		(sheetname "/PD and TB DC-DC/")
		(sheetfile "PD_and_TB_DC_DC.kicad_sch")
		(attr smd)
		(fp_rect
			(start -0.925 -0.47)
			(end 0.925 0.47)
			(stroke
				(width 0.05)
				(type default)
			)
			(fill no)
			(layer "F.CrtYd")
		)
		(fp_rect
			(start -0.5 -0.25)
			(end 0.5 0.25)
			(stroke
				(width 0.15)
				(type solid)
			)
			(fill no)
			(layer "F.Fab")
		)
		(fp_text user "${REFERENCE}"
			(at -0.95 3.168 180)
			(layer "F.Fab")
			(effects
				(font
					(size 0.7 0.7)
					(thickness 0.15)
				)
				(justify left bottom)
			)
		)
		(fp_text user "License: Apache-2.0"
			(at -0.95 5.169 180)
			(layer "F.Fab")
			(effects
				(font
					(size 0.7 0.7)
					(thickness 0.15)
				)
				(justify left bottom)
			)
		)
		(fp_text user "Author: Antmicro"
			(at -0.95 4.169 180)
			(layer "F.Fab")
			(effects
				(font
					(size 0.7 0.7)
					(thickness 0.15)
				)
				(justify left bottom)
			)
		)
		(pad "1" smd roundrect
			(at -0.48 0 180)
			(size 0.59 0.64)
			(layers "F.Cu" "F.Mask" "F.Paste")
			(roundrect_rratio 0.25)
			(net 166 "Net-(U2-FB)")
			(pintype "passive")
		)
		(pad "2" smd roundrect
			(at 0.48 0 180)
			(size 0.59 0.64)
			(layers "F.Cu" "F.Mask" "F.Paste")
			(roundrect_rratio 0.25)
			(net 399 "Net-(D4-A)")
			(pintype "passive")
		)
	)
	(footprint "antmicro-footprints:C_0603_1608Metric_EIA"
		(layer "F.Cu")
		(at 137.305 99.774998 -90)
		(descr "Capacitor SMD 0603, IPC-7351 Density Level A")
		(tags "Capacitor 0603")
		(property "Reference" "C265"
			(at -9.274999 -36.945 270)
			(layer "F.SilkS")
			(effects
				(font
					(size 0.7 0.7)
					(thickness 0.15)
				)
			)
		)
		(property "Value" "C_22u_16V_0603"
			(at -1.42757 1.770288 270)
			(layer "F.Fab")
			(effects
				(font
					(size 0.7 0.7)
					(thickness 0.15)
				)
				(justify left bottom)
			)
		)
		(property "Datasheet" "https://product.samsungsem.com/mlcc/CL10A226MO7JZN.do"
			(at 0 0 270)
			(layer "F.Fab")
			(hide yes)
			(effects
				(font
					(size 1.27 1.27)
					(thickness 0.15)
				)
			)
		)
		(property "Description" "SMD Multilayer Ceramic Capacitor"
			(at 0 0 270)
			(layer "F.Fab")
			(hide yes)
			(effects
				(font
					(size 1.27 1.27)
					(thickness 0.15)
				)
			)
		)
		(property "MPN" "CL10A226MO7JZNC"
			(at 0 0 270)
			(unlocked yes)
			(layer "F.Fab")
			(hide yes)
			(effects
				(font
					(size 1 1)
					(thickness 0.15)
				)
			)
		)
		(property "Manufacturer" "Samsung Electro-Mechanics"
			(at 0 0 270)
			(unlocked yes)
			(layer "F.Fab")
			(hide yes)
			(effects
				(font
					(size 1 1)
					(thickness 0.15)
				)
			)
		)
		(property "License" "Apache-2.0"
			(at 0 0 270)
			(unlocked yes)
			(layer "F.Fab")
			(hide yes)
			(effects
				(font
					(size 1 1)
					(thickness 0.15)
				)
			)
		)
		(property "Author" "Antmicro"
			(at 0 0 270)
			(unlocked yes)
			(layer "F.Fab")
			(hide yes)
			(effects
				(font
					(size 1 1)
					(thickness 0.15)
				)
			)
		)
		(property "Val" "22u"
			(at 0 0 270)
			(unlocked yes)
			(layer "F.Fab")
			(hide yes)
			(effects
				(font
					(size 1 1)
					(thickness 0.15)
				)
			)
		)
		(property "Voltage" "16V"
			(at 0 0 270)
			(unlocked yes)
			(layer "F.Fab")
			(hide yes)
			(effects
				(font
					(size 1 1)
					(thickness 0.15)
				)
			)
		)
		(property "Dielectric" ""
			(at 0 0 270)
			(unlocked yes)
			(layer "F.Fab")
			(hide yes)
			(effects
				(font
					(size 1 1)
					(thickness 0.15)
				)
			)
		)
		(sheetname "/X710-AT2 power/")
		(sheetfile "x710-at2-power.kicad_sch")
		(attr smd)
		(fp_line
			(start -0.15 0.55)
			(end 0.15 0.55)
			(stroke
				(width 0.15)
				(type solid)
			)
			(layer "F.SilkS")
		)
		(fp_line
			(start -0.15 -0.55)
			(end 0.15 -0.55)
			(stroke
				(width 0.15)
				(type solid)
			)
			(layer "F.SilkS")
		)
		(fp_rect
			(start -1.25 -0.65)
			(end 1.25 0.65)
			(stroke
				(width 0.05)
				(type solid)
			)
			(fill no)
			(layer "F.CrtYd")
		)
		(fp_rect
			(start -0.8 -0.45)
			(end 0.8 0.45)
			(stroke
				(width 0.15)
				(type solid)
			)
			(fill no)
			(layer "F.Fab")
		)
		(fp_text user "License: Apache-2.0"
			(at -1.682 5.895 270)
			(layer "F.Fab")
			(effects
				(font
					(size 0.7 0.7)
					(thickness 0.15)
				)
				(justify left bottom)
			)
		)
		(fp_text user "${REFERENCE}"
			(at -1.682 3.895 270)
			(layer "F.Fab")
			(effects
				(font
					(size 0.7 0.7)
					(thickness 0.15)
				)
				(justify left bottom)
			)
		)
		(fp_text user "Author: Antmicro"
			(at -1.682 4.894 270)
			(layer "F.Fab")
			(effects
				(font
					(size 0.7 0.7)
					(thickness 0.15)
				)
				(justify left bottom)
			)
		)
		(pad "1" smd roundrect
			(at -0.7 0 270)
			(size 0.8 1.1)
			(layers "F.Cu" "F.Mask" "F.Paste")
			(roundrect_rratio 0.2)
			(net 23 "GND")
			(pintype "passive")
		)
		(pad "2" smd roundrect
			(at 0.7 0 270)
			(size 0.8 1.1)
			(layers "F.Cu" "F.Mask" "F.Paste")
			(roundrect_rratio 0.2)
			(net 9 "VCCD")
			(pintype "passive")
		)
	)
	(footprint "antmicro-footprints:R_0402_1005Metric"
		(layer "F.Cu")
		(at 116.99 72.9)
		(descr "Resistor SMD 0402")
		(tags "resistor SMD 0402")
		(property "Reference" "R217"
			(at 3.6 -10.5 0)
			(layer "F.SilkS")
			(effects
				(font
					(size 0.7 0.7)
					(thickness 0.15)
				)
				(justify left bottom)
			)
		)
		(property "Value" "R_10k_0402"
			(at -1.011843 1.772047 0)
			(layer "F.Fab")
			(effects
				(font
					(size 0.7 0.7)
					(thickness 0.15)
				)
				(justify left bottom)
			)
		)
		(property "Datasheet" "https://www.bourns.com/docs/product-datasheets/cr.pdf"
			(at 0 0 0)
			(layer "F.Fab")
			(hide yes)
			(effects
				(font
					(size 1.27 1.27)
					(thickness 0.15)
				)
			)
		)
		(property "Description" "SMD Chip Resistor, 10 kohm, ± 1%, 62.5 mW, 0402 [1005 Metric], Thick Film, General Purpose"
			(at 0 0 0)
			(layer "F.Fab")
			(hide yes)
			(effects
				(font
					(size 1.27 1.27)
					(thickness 0.15)
				)
			)
		)
		(property "MPN" "CR0402-FX-1002GLF"
			(at 0 0 0)
			(unlocked yes)
			(layer "F.Fab")
			(hide yes)
			(effects
				(font
					(size 1 1)
					(thickness 0.15)
				)
			)
		)
		(property "Manufacturer" "Bourns"
			(at 0 0 0)
			(unlocked yes)
			(layer "F.Fab")
			(hide yes)
			(effects
				(font
					(size 1 1)
					(thickness 0.15)
				)
			)
		)
		(property "License" "Apache-2.0"
			(at 0 0 0)
			(unlocked yes)
			(layer "F.Fab")
			(hide yes)
			(effects
				(font
					(size 1 1)
					(thickness 0.15)
				)
			)
		)
		(property "Author" "Antmicro"
			(at 0 0 0)
			(unlocked yes)
			(layer "F.Fab")
			(hide yes)
			(effects
				(font
					(size 1 1)
					(thickness 0.15)
				)
			)
		)
		(property "Val" "10k"
			(at 0 0 0)
			(unlocked yes)
			(layer "F.Fab")
			(hide yes)
			(effects
				(font
					(size 1 1)
					(thickness 0.15)
				)
			)
		)
		(property "Tolerance" "1%"
			(at 0 0 0)
			(unlocked yes)
			(layer "F.Fab")
			(hide yes)
			(effects
				(font
					(size 1 1)
					(thickness 0.15)
				)
			)
		)
		(sheetname "/Fan controller/")
		(sheetfile "fan-controller.kicad_sch")
		(attr smd)
		(fp_rect
			(start -0.925 -0.47)
			(end 0.925 0.47)
			(stroke
				(width 0.05)
				(type default)
			)
			(fill no)
			(layer "F.CrtYd")
		)
		(fp_rect
			(start -0.5 -0.25)
			(end 0.5 0.25)
			(stroke
				(width 0.15)
				(type solid)
			)
			(fill no)
			(layer "F.Fab")
		)
		(fp_text user "License: Apache-2.0"
			(at -0.95 5.169 0)
			(layer "F.Fab")
			(effects
				(font
					(size 0.7 0.7)
					(thickness 0.15)
				)
				(justify left bottom)
			)
		)
		(fp_text user "Author: Antmicro"
			(at -0.95 4.169 0)
			(layer "F.Fab")
			(effects
				(font
					(size 0.7 0.7)
					(thickness 0.15)
				)
				(justify left bottom)
			)
		)
		(fp_text user "${REFERENCE}"
			(at -0.95 3.168 0)
			(layer "F.Fab")
			(effects
				(font
					(size 0.7 0.7)
					(thickness 0.15)
				)
				(justify left bottom)
			)
		)
		(pad "1" smd roundrect
			(at -0.48 0)
			(size 0.59 0.64)
			(layers "F.Cu" "F.Mask" "F.Paste")
			(roundrect_rratio 0.25)
			(net 446 "Net-(R216-Pad1)")
			(pintype "passive")
		)
		(pad "2" smd roundrect
			(at 0.48 0)
			(size 0.59 0.64)
			(layers "F.Cu" "F.Mask" "F.Paste")
			(roundrect_rratio 0.25)
			(net 151 "/Fan controller/SENSE")
			(pintype "passive")
		)
	)
	(footprint "antmicro-footprints:C_0402_1005Metric"
		(layer "F.Cu")
		(at 156.915 95.530499)
		(descr "Capacitor SMD 0402")
		(tags "capacitor SMD 0402")
		(property "Reference" "C281"
			(at 23.294999 19.625001 0)
			(layer "F.SilkS")
			(effects
				(font
					(size 0.7 0.7)
					(thickness 0.15)
				)
			)
		)
		(property "Value" "C_5p6_0402"
			(at -1.022927 2.155213 0)
			(layer "F.Fab")
			(effects
				(font
					(size 0.7 0.7)
					(thickness 0.15)
				)
				(justify left bottom)
			)
		)
		(property "Datasheet" "https://www.mouser.com/datasheet/3/76/2/GCM1555C1H5R6BA16_01A.pdf"
			(at 0 0 0)
			(layer "F.Fab")
			(hide yes)
			(effects
				(font
					(size 1.27 1.27)
					(thickness 0.15)
				)
			)
		)
		(property "Description" "Multilayer Ceramic Capacitors MLCC - SMD/SMT 5.6 pF 50 VDC 0.1 pF 0402 C0G (NP0) AEC-Q200"
			(at 0 0 0)
			(layer "F.Fab")
			(hide yes)
			(effects
				(font
					(size 1.27 1.27)
					(thickness 0.15)
				)
			)
		)
		(property "MPN" "GCM1555C1H5R6BA16D"
			(at 0 0 0)
			(unlocked yes)
			(layer "F.Fab")
			(hide yes)
			(effects
				(font
					(size 1 1)
					(thickness 0.15)
				)
			)
		)
		(property "Manufacturer" "Murata"
			(at 0 0 0)
			(unlocked yes)
			(layer "F.Fab")
			(hide yes)
			(effects
				(font
					(size 1 1)
					(thickness 0.15)
				)
			)
		)
		(property "License" "Apache-2.0"
			(at 0 0 0)
			(unlocked yes)
			(layer "F.Fab")
			(hide yes)
			(effects
				(font
					(size 1 1)
					(thickness 0.15)
				)
			)
		)
		(property "Author" "Antmicro"
			(at 0 0 0)
			(unlocked yes)
			(layer "F.Fab")
			(hide yes)
			(effects
				(font
					(size 1 1)
					(thickness 0.15)
				)
			)
		)
		(property "Val" "5p6"
			(at 0 0 0)
			(unlocked yes)
			(layer "F.Fab")
			(hide yes)
			(effects
				(font
					(size 1 1)
					(thickness 0.15)
				)
			)
		)
		(property "Voltage" "50V"
			(at 0 0 0)
			(unlocked yes)
			(layer "F.Fab")
			(hide yes)
			(effects
				(font
					(size 1 1)
					(thickness 0.15)
				)
			)
		)
		(property "Dielectric" "C0G"
			(at 0 0 0)
			(unlocked yes)
			(layer "F.Fab")
			(hide yes)
			(effects
				(font
					(size 1 1)
					(thickness 0.15)
				)
			)
		)
		(sheetname "/X710-AT2 Misc/")
		(sheetfile "x710-at2-mics.kicad_sch")
		(attr smd)
		(fp_rect
			(start -0.925 -0.47)
			(end 0.925 0.47)
			(stroke
				(width 0.05)
				(type default)
			)
			(fill no)
			(layer "F.CrtYd")
		)
		(fp_line
			(start -0.494 -0.25)
			(end 0.504 -0.25)
			(stroke
				(width 0.15)
				(type solid)
			)
			(layer "F.Fab")
		)
		(fp_line
			(start -0.494 0.248)
			(end -0.494 -0.25)
			(stroke
				(width 0.15)
				(type solid)
			)
			(layer "F.Fab")
		)
		(fp_line
			(start 0.504 -0.25)
			(end 0.504 0.248)
			(stroke
				(width 0.15)
				(type solid)
			)
			(layer "F.Fab")
		)
		(fp_line
			(start 0.504 0.248)
			(end -0.494 0.248)
			(stroke
				(width 0.15)
				(type solid)
			)
			(layer "F.Fab")
		)
		(fp_text user "${REFERENCE}"
			(at -0.939 4.599 0)
			(layer "F.Fab")
			(effects
				(font
					(size 0.7 0.7)
					(thickness 0.15)
				)
				(justify left bottom)
			)
		)
		(fp_text user "Author: Antmicro"
			(at -0.939 3.399 0)
			(layer "F.Fab")
			(effects
				(font
					(size 0.7 0.7)
					(thickness 0.15)
				)
				(justify left bottom)
			)
		)
		(fp_text user "License: Apache-2.0"
			(at -0.939 5.799 0)
			(layer "F.Fab")
			(effects
				(font
					(size 0.7 0.7)
					(thickness 0.15)
				)
				(justify left bottom)
			)
		)
		(pad "1" smd roundrect
			(at -0.48 0)
			(size 0.59 0.64)
			(layers "F.Cu" "F.Mask" "F.Paste")
			(roundrect_rratio 0.25)
			(net 23 "GND")
			(pintype "passive")
		)
		(pad "2" smd roundrect
			(at 0.48 0)
			(size 0.59 0.64)
			(layers "F.Cu" "F.Mask" "F.Paste")
			(roundrect_rratio 0.25)
			(net 59 "/X710-AT2 Misc/50MHZ_XTAL_R.-")
			(pintype "passive")
		)
	)
	(footprint "antmicro-footprints:C_0603_1608Metric_EIA"
		(layer "F.Cu")
		(at 151.850002 103.050001 -90)
		(descr "Capacitor SMD 0603, IPC-7351 Density Level A")
		(tags "Capacitor 0603")
		(property "Reference" "C141"
			(at 17.649996 -14.449998 270)
			(layer "F.SilkS")
			(effects
				(font
					(size 0.7 0.7)
					(thickness 0.15)
				)
			)
		)
		(property "Value" "C_22u_16V_0603"
			(at -1.42757 1.770288 270)
			(layer "F.Fab")
			(effects
				(font
					(size 0.7 0.7)
					(thickness 0.15)
				)
				(justify left bottom)
			)
		)
		(property "Datasheet" "https://product.samsungsem.com/mlcc/CL10A226MO7JZN.do"
			(at 0 0 270)
			(layer "F.Fab")
			(hide yes)
			(effects
				(font
					(size 1.27 1.27)
					(thickness 0.15)
				)
			)
		)
		(property "Description" "SMD Multilayer Ceramic Capacitor"
			(at 0 0 270)
			(layer "F.Fab")
			(hide yes)
			(effects
				(font
					(size 1.27 1.27)
					(thickness 0.15)
				)
			)
		)
		(property "MPN" "CL10A226MO7JZNC"
			(at 0 0 270)
			(unlocked yes)
			(layer "F.Fab")
			(hide yes)
			(effects
				(font
					(size 1 1)
					(thickness 0.15)
				)
			)
		)
		(property "Manufacturer" "Samsung Electro-Mechanics"
			(at 0 0 270)
			(unlocked yes)
			(layer "F.Fab")
			(hide yes)
			(effects
				(font
					(size 1 1)
					(thickness 0.15)
				)
			)
		)
		(property "License" "Apache-2.0"
			(at 0 0 270)
			(unlocked yes)
			(layer "F.Fab")
			(hide yes)
			(effects
				(font
					(size 1 1)
					(thickness 0.15)
				)
			)
		)
		(property "Author" "Antmicro"
			(at 0 0 270)
			(unlocked yes)
			(layer "F.Fab")
			(hide yes)
			(effects
				(font
					(size 1 1)
					(thickness 0.15)
				)
			)
		)
		(property "Val" "22u"
			(at 0 0 270)
			(unlocked yes)
			(layer "F.Fab")
			(hide yes)
			(effects
				(font
					(size 1 1)
					(thickness 0.15)
				)
			)
		)
		(property "Voltage" "16V"
			(at 0 0 270)
			(unlocked yes)
			(layer "F.Fab")
			(hide yes)
			(effects
				(font
					(size 1 1)
					(thickness 0.15)
				)
			)
		)
		(property "Dielectric" ""
			(at 0 0 270)
			(unlocked yes)
			(layer "F.Fab")
			(hide yes)
			(effects
				(font
					(size 1 1)
					(thickness 0.15)
				)
			)
		)
		(sheetname "/X710 DCDC converters/")
		(sheetfile "DCDC_converters_X710.kicad_sch")
		(attr smd)
		(fp_line
			(start -0.15 0.55)
			(end 0.15 0.55)
			(stroke
				(width 0.15)
				(type solid)
			)
			(layer "F.SilkS")
		)
		(fp_line
			(start -0.15 -0.55)
			(end 0.15 -0.55)
			(stroke
				(width 0.15)
				(type solid)
			)
			(layer "F.SilkS")
		)
		(fp_rect
			(start -1.25 -0.65)
			(end 1.25 0.65)
			(stroke
				(width 0.05)
				(type solid)
			)
			(fill no)
			(layer "F.CrtYd")
		)
		(fp_rect
			(start -0.8 -0.45)
			(end 0.8 0.45)
			(stroke
				(width 0.15)
				(type solid)
			)
			(fill no)
			(layer "F.Fab")
		)
		(fp_text user "License: Apache-2.0"
			(at -1.682 5.895 270)
			(layer "F.Fab")
			(effects
				(font
					(size 0.7 0.7)
					(thickness 0.15)
				)
				(justify left bottom)
			)
		)
		(fp_text user "Author: Antmicro"
			(at -1.682 4.894 270)
			(layer "F.Fab")
			(effects
				(font
					(size 0.7 0.7)
					(thickness 0.15)
				)
				(justify left bottom)
			)
		)
		(fp_text user "${REFERENCE}"
			(at -1.682 3.895 270)
			(layer "F.Fab")
			(effects
				(font
					(size 0.7 0.7)
					(thickness 0.15)
				)
				(justify left bottom)
			)
		)
		(pad "1" smd roundrect
			(at -0.7 0 270)
			(size 0.8 1.1)
			(layers "F.Cu" "F.Mask" "F.Paste")
			(roundrect_rratio 0.2)
			(net 23 "GND")
			(pintype "passive")
		)
		(pad "2" smd roundrect
			(at 0.7 0 270)
			(size 0.8 1.1)
			(layers "F.Cu" "F.Mask" "F.Paste")
			(roundrect_rratio 0.2)
			(net 338 "/X710 DCDC converters/+1V88_OUT")
			(pintype "passive")
		)
	)
)
